# TIMECARD (Time Appliance Project (Time Card)) — schematic netlist excerpt (pin names and nets, part order shuffled) for the footprints in the layout excerpt that follows; sources: Cadence DE-HDL packaged netlist, KiCad conversion of R4006-B0001-02_R01.brd

R478  RESISTOR  100KOHM 1%  pkg SMC_0402R_H016  page 24 : \1\ = FT4232_I2C_SCL ; \2\ = XP3R3V_FT4232
R144  RESISTOR  33OHM 1%  pkg SMC_0402R_H016  page 16 : \1\ = PCA9546_I2C_SDA ; \2\ = R_PCA9546_I2C_SDA

(kicad_pcb
	(version 20260206)
	(generator "pcbnew")
	(generator_version "10.0")
	(general
		(thickness 1.6)
		(legacy_teardrops no)
	)
	(paper "A4")
	(title_block
		(title "timecard-production-celestica-r4006 — R4006-B0001-02_R01.brd")
		(comment 1 "Time Appliance Project (Time Card) / footprints 1065-1066 of 1113")
	)
	(layers
		(0 "F.Cu" signal "TOP")
		(4 "In1.Cu" signal "L02_GND1")
		(6 "In2.Cu" signal "L03_SIG1")
		(8 "In3.Cu" signal "L04_GND2")
		(10 "In4.Cu" signal "L05_VCC1")
		(12 "In5.Cu" signal "L06_VCC2")
		(14 "In6.Cu" signal "L07_GND3")
		(16 "In7.Cu" signal "L08_SIG2")
		(18 "In8.Cu" signal "L09_GND4")
		(2 "B.Cu" signal "BOTTOM")
		(9 "F.Adhes" user "F.Adhesive")
		(11 "B.Adhes" user "B.Adhesive")
		(13 "F.Paste" user "Package Geometry/Pastemask Top")
		(15 "B.Paste" user "Package Geometry/Pastemask Bottom")
		(5 "F.SilkS" user "Ref Des/Silkscreen Top")
		(7 "B.SilkS" user "Ref Des/Silkscreen Bottom")
		(1 "F.Mask" user "Board Geometry/Soldermask Top")
		(3 "B.Mask" user "Board Geometry/Soldermask Bottom")
		(17 "Dwgs.User" user "User.Drawings")
		(19 "Cmts.User" user "User.Comments")
		(21 "Eco1.User" user "User.Eco1")
		(23 "Eco2.User" user "User.Eco2")
		(25 "Edge.Cuts" user "Board Geometry/Outline")
		(27 "Margin" user)
		(31 "F.CrtYd" user "Package Geometry/Place Bound Top")
		(29 "B.CrtYd" user "Package Geometry/Place Bound Bottom")
		(35 "F.Fab" user "Ref Des/Assembly Top")
		(33 "B.Fab" user "Ref Des/Assembly Bottom")
	)
	(footprint ""
		(layer "B.Cu")
		(at 18.415 -82.423 180)
		(property "Reference" "R478"
			(at -3.683 -0.42037 0)
			(unlocked yes)
			(layer "B.SilkS")
			(effects
				(font
					(size 0.7874 0.5842)
					(thickness 0.1524)
				)
				(justify mirror)
			)
		)
		(property "Value" "VAL*"
			(at -0.02032 2.13233 180)
			(unlocked yes)
			(layer "B.Fab")
			(hide yes)
			(effects
				(font
					(size 0.7874 0.5842)
					(thickness 0.1524)
				)
				(justify mirror)
			)
		)
		(property "Tolerance" "TOL*"
			(at -0.044704 3.05435 180)
			(unlocked yes)
			(layer "Cmts.User")
			(hide yes)
			(effects
				(font
					(size 0.7874 0.5842)
					(thickness 0.1524)
				)
				(justify mirror)
			)
		)
		(property "User Part Number" "PARTNUM*"
			(at -0.02032 4.024884 180)
			(unlocked yes)
			(layer "Cmts.User")
			(hide yes)
			(effects
				(font
					(size 0.7874 0.5842)
					(thickness 0.1524)
				)
				(justify mirror)
			)
		)
		(property "Device Type" "RESISTOR-G155-11003-01,100KOHMA"
			(at -0.008382 1.210564 180)
			(unlocked yes)
			(layer "B.Fab")
			(hide yes)
			(effects
				(font
					(size 0.7874 0.5842)
					(thickness 0.1524)
				)
				(justify mirror)
			)
		)
		(duplicate_pad_numbers_are_jumpers no)
		(fp_line
			(start 1.143 0.5588)
			(end -1.143 0.5588)
			(stroke
				(width 0.1)
				(type default)
			)
			(layer "B.SilkS")
		)
		(fp_line
			(start 1.143 -0.5588)
			(end 1.143 0.5588)
			(stroke
				(width 0.1)
				(type default)
			)
			(layer "B.SilkS")
		)
		(fp_line
			(start -1.143 0.5588)
			(end -1.143 -0.5588)
			(stroke
				(width 0.1)
				(type default)
			)
			(layer "B.SilkS")
		)
		(fp_line
			(start -1.143 -0.5588)
			(end 1.143 -0.5588)
			(stroke
				(width 0.1)
				(type default)
			)
			(layer "B.SilkS")
		)
		(fp_poly
			(pts
				(xy 1.143 0.5588) (xy -1.143 0.5588) (xy -1.143 -0.5588) (xy 1.143 -0.5588)
			)
			(stroke
				(width 0)
				(type default)
			)
			(fill no)
			(layer "B.CrtYd")
		)
		(fp_line
			(start 0.508 0.3048)
			(end -0.508 0.3048)
			(stroke
				(width 0.1)
				(type default)
			)
			(layer "B.Fab")
		)
		(fp_line
			(start 0.508 -0.3048)
			(end 0.508 0.3048)
			(stroke
				(width 0.1)
				(type default)
			)
			(layer "B.Fab")
		)
		(fp_line
			(start -0.508 0.3048)
			(end -0.508 -0.3048)
			(stroke
				(width 0.1)
				(type default)
			)
			(layer "B.Fab")
		)
		(fp_line
			(start -0.508 -0.3048)
			(end 0.508 -0.3048)
			(stroke
				(width 0.1)
				(type default)
			)
			(layer "B.Fab")
		)
		(pad "1" smd rect
			(at 0.5334 0)
			(size 0.7112 0.6096)
			(layers "B.Cu" "B.Mask" "B.Paste")
			(net "FT4232_I2C_SCL")
		)
		(pad "2" smd rect
			(at -0.5334 0)
			(size 0.7112 0.6096)
			(layers "B.Cu" "B.Mask" "B.Paste")
			(net "XP3R3V_FT4232")
		)
		(zone
			(layer "B.Cu")
			(hatch none 0.5)
			(connect_pads
				(clearance 0)
			)
			(min_thickness 0.25)
			(keepout
				(tracks not_allowed)
				(vias allowed)
				(pads allowed)
				(copperpour not_allowed)
				(footprints allowed)
			)
			(placement
				(enabled no)
				(sheetname "")
			)
			(fill
				(thermal_gap 0.5)
				(thermal_bridge_width 0.5)
				(island_removal_mode 0)
			)
			(polygon
				(pts
					(xy 18.3388 -82.7278) (xy 18.3388 -82.1182) (xy 18.4912 -82.1182) (xy 18.4912 -82.7278)
				)
			)
		)
		(zone
			(layer "B.Cu")
			(hatch none 0.5)
			(connect_pads
				(clearance 0)
			)
			(min_thickness 0.25)
			(keepout
				(tracks allowed)
				(vias not_allowed)
				(pads allowed)
				(copperpour not_allowed)
				(footprints allowed)
			)
			(placement
				(enabled no)
				(sheetname "")
			)
			(fill
				(thermal_gap 0.5)
				(thermal_bridge_width 0.5)
				(island_removal_mode 0)
			)
			(polygon
				(pts
					(xy 18.3388 -82.7278) (xy 18.3388 -82.1182) (xy 18.4912 -82.1182) (xy 18.4912 -82.7278)
				)
			)
		)
	)
	(footprint ""
		(layer "B.Cu")
		(at 17.7038 -40.6146 180)
		(property "Reference" "R144"
			(at 0.4318 1.12903 0)
			(unlocked yes)
			(layer "B.SilkS")
			(effects
				(font
					(size 0.7874 0.5842)
					(thickness 0.1524)
				)
				(justify mirror)
			)
		)
		(property "Value" "VAL*"
			(at -0.02032 2.13233 180)
			(unlocked yes)
			(layer "B.Fab")
			(hide yes)
			(effects
				(font
					(size 0.7874 0.5842)
					(thickness 0.1524)
				)
				(justify mirror)
			)
		)
		(property "Device Type" "RESISTOR-G155-133R0-01,33OHM,1%"
			(at -0.008382 1.210564 180)
			(unlocked yes)
			(layer "B.Fab")
			(hide yes)
			(effects
				(font
					(size 0.7874 0.5842)
					(thickness 0.1524)
				)
				(justify mirror)
			)
		)
		(property "User Part Number" "PARTNUM*"
			(at -0.02032 4.024884 180)
			(unlocked yes)
			(layer "Cmts.User")
			(hide yes)
			(effects
				(font
					(size 0.7874 0.5842)
					(thickness 0.1524)
				)
				(justify mirror)
			)
		)
		(property "Tolerance" "TOL*"
			(at -0.044704 3.05435 180)
			(unlocked yes)
			(layer "Cmts.User")
			(hide yes)
			(effects
				(font
					(size 0.7874 0.5842)
					(thickness 0.1524)
				)
				(justify mirror)
			)
		)
		(duplicate_pad_numbers_are_jumpers no)
		(fp_line
			(start 1.143 0.5588)
			(end -1.143 0.5588)
			(stroke
				(width 0.1)
				(type default)
			)
			(layer "B.SilkS")
		)
		(fp_line
			(start 1.143 -0.5588)
			(end 1.143 0.5588)
			(stroke
				(width 0.1)
				(type default)
			)
			(layer "B.SilkS")
		)
		(fp_line
			(start -1.143 0.5588)
			(end -1.143 -0.5588)
			(stroke
				(width 0.1)
				(type default)
			)
			(layer "B.SilkS")
		)
		(fp_line
			(start -1.143 -0.5588)
			(end 1.143 -0.5588)
			(stroke
				(width 0.1)
				(type default)
			)
			(layer "B.SilkS")
		)
		(fp_rect
			(start 1.143 0.5588)
			(end -1.143 -0.5588)
			(stroke
				(width 0)
				(type default)
			)
			(fill no)
			(layer "B.CrtYd")
		)
		(fp_line
			(start 0.508 0.3048)
			(end -0.508 0.3048)
			(stroke
				(width 0.1)
				(type default)
			)
			(layer "B.Fab")
		)
		(fp_line
			(start 0.508 -0.3048)
			(end 0.508 0.3048)
			(stroke
				(width 0.1)
				(type default)
			)
			(layer "B.Fab")
		)
		(fp_line
			(start -0.508 0.3048)
			(end -0.508 -0.3048)
			(stroke
				(width 0.1)
				(type default)
			)
			(layer "B.Fab")
		)
		(fp_line
			(start -0.508 -0.3048)
			(end 0.508 -0.3048)
			(stroke
				(width 0.1)
				(type default)
			)
			(layer "B.Fab")
		)
		(pad "1" smd rect
			(at 0.5334 0)
			(size 0.7112 0.6096)
			(layers "B.Cu" "B.Mask" "B.Paste")
			(net "PCA9546_I2C_SDA")
		)
		(pad "2" smd rect
			(at -0.5334 0)
			(size 0.7112 0.6096)
			(layers "B.Cu" "B.Mask" "B.Paste")
			(net "R_PCA9546_I2C_SDA")
		)
		(zone
			(layer "B.Cu")
			(hatch none 0.5)
			(connect_pads
				(clearance 0)
			)
			(min_thickness 0.25)
			(keepout
				(tracks allowed)
				(vias not_allowed)
				(pads allowed)
				(copperpour not_allowed)
				(footprints allowed)
			)
			(placement
				(enabled no)
				(sheetname "")
			)
			(fill
				(thermal_gap 0.5)
				(thermal_bridge_width 0.5)
				(island_removal_mode 0)
			)
			(polygon
				(pts
					(xy 17.6276 -40.9194) (xy 17.6276 -40.3098) (xy 17.78 -40.3098) (xy 17.78 -40.9194)
				)
			)
		)
	)
)
